# T6G (Grand Teton) — schematic netlist excerpt (pin names and nets, part order shuffled) for the footprints in the layout excerpt that follows; sources: Cadence DE-HDL packaged netlist, KiCad conversion of 04192023_DAF0TMB3IC0_F0TG_MB_C_brd_V02_OCP.brd

PC402_C1P1_3  Q_CAP  2.2UF 10V 10% X6S  pkg C0402  page 219 : A = PVDDCR_CPU1_P1_PVCC ; B = GND
C909  Q_CAP_DIFFBUS  DIFF BUS_0.22UF 6.3V 20% X6S  pkg C0201  page 63 : \1\ = P5E_CPU0_P0_TX_C_DP<12> ; \2\ = P5E_CPU0_P0_TX_DP<12>

PL32  Q_INDUCTOR4P_14  150NH IND  pkg L_TLM117513Q-151QL_11X7-5XA  page 212
  \1\  = SW_PVDDCR_CPU0_P1_SW4
  \2\  = IND_CPU0_P1_CPL3
  \3\  = GND
  \4\  = PVDDCR_CPU0_P1

(kicad_pcb
	(version 20260206)
	(generator "pcbnew")
	(generator_version "10.0")
	(general
		(thickness 1.6)
		(legacy_teardrops no)
	)
	(paper "A4")
	(title_block
		(title "04192023_DAF0TMB3IC0_F0TG_MB_C_brd_V02_OCP.brd")
		(comment 1 "Grand Teton / footprints 3659-3661 of 8354")
	)
	(layers
		(0 "F.Cu" signal "TOP")
		(4 "In1.Cu" signal "GND")
		(6 "In2.Cu" signal "IN1")
		(8 "In3.Cu" signal "GND1")
		(10 "In4.Cu" signal "IN2")
		(12 "In5.Cu" signal "GND2")
		(14 "In6.Cu" signal "IN3")
		(16 "In7.Cu" signal "GND3")
		(18 "In8.Cu" signal "VCC")
		(20 "In9.Cu" signal "VCC1")
		(22 "In10.Cu" signal "GND4")
		(24 "In11.Cu" signal "IN4")
		(26 "In12.Cu" signal "GND5")
		(28 "In13.Cu" signal "IN5")
		(30 "In14.Cu" signal "GND6")
		(32 "In15.Cu" signal "IN6")
		(34 "In16.Cu" signal "GND7")
		(2 "B.Cu" signal "BOTTOM")
		(9 "F.Adhes" user "F.Adhesive")
		(11 "B.Adhes" user "B.Adhesive")
		(13 "F.Paste" user "Package Geometry/Pastemask Top")
		(15 "B.Paste" user "Package Geometry/Pastemask Bottom")
		(5 "F.SilkS" user "Ref Des/Silkscreen Top")
		(7 "B.SilkS" user "Ref Des/Silkscreen Bottom")
		(1 "F.Mask" user "Board Geometry/Soldermask Top")
		(3 "B.Mask" user "Board Geometry/Soldermask Bottom")
		(17 "Dwgs.User" user "User.Drawings")
		(19 "Cmts.User" user "User.Comments")
		(21 "Eco1.User" user "User.Eco1")
		(23 "Eco2.User" user "User.Eco2")
		(25 "Edge.Cuts" user "Board Geometry/Outline")
		(27 "Margin" user)
		(31 "F.CrtYd" user "Package Geometry/Place Bound Top")
		(29 "B.CrtYd" user "Package Geometry/Place Bound Bottom")
		(35 "F.Fab" user "Ref Des/Assembly Top")
		(33 "B.Fab" user "Ref Des/Assembly Bottom")
	)
	(footprint ""
		(layer "F.Cu")
		(at 108.092748 -187.492894 180)
		(property "Reference" "PL32"
			(at -0.856488 6.245098 0)
			(unlocked yes)
			(layer "F.SilkS")
			(effects
				(font
					(size 0.7874 0.5842)
					(thickness 0.1524)
				)
				(justify left)
			)
		)
		(property "Value" ""
			(at 0 0 180)
			(layer "F.Fab")
			(effects
				(font
					(size 1.27 1.27)
				)
			)
		)
		(duplicate_pad_numbers_are_jumpers no)
		(fp_line
			(start 3.750056 5.500116)
			(end 3.750056 -5.500116)
			(stroke
				(width 0.1524)
				(type default)
			)
			(layer "F.SilkS")
		)
		(fp_line
			(start 3.750056 -5.500116)
			(end 2.393442 -5.500116)
			(stroke
				(width 0.1524)
				(type default)
			)
			(layer "F.SilkS")
		)
		(fp_line
			(start 2.393442 5.500116)
			(end 3.750056 5.500116)
			(stroke
				(width 0.1524)
				(type default)
			)
			(layer "F.SilkS")
		)
		(fp_line
			(start -2.393442 5.500116)
			(end -3.750056 5.500116)
			(stroke
				(width 0.1524)
				(type default)
			)
			(layer "F.SilkS")
		)
		(fp_line
			(start -3.750056 5.500116)
			(end -3.750056 -5.500116)
			(stroke
				(width 0.1524)
				(type default)
			)
			(layer "F.SilkS")
		)
		(fp_line
			(start -3.750056 -5.500116)
			(end -2.393442 -5.500116)
			(stroke
				(width 0.1524)
				(type default)
			)
			(layer "F.SilkS")
		)
		(fp_poly
			(pts
				(xy 3.963416 -4.623562) (xy 4.741418 -5.01269) (xy 4.741418 -4.234434)
			)
			(stroke
				(width 0)
				(type default)
			)
			(fill yes)
			(layer "F.SilkS")
		)
		(fp_line
			(start 3.750056 5.500116)
			(end 3.750056 -5.500116)
			(stroke
				(width 0.1)
				(type default)
			)
			(layer "F.Fab")
		)
		(fp_line
			(start 3.750056 -5.500116)
			(end -3.750056 -5.500116)
			(stroke
				(width 0.1)
				(type default)
			)
			(layer "F.Fab")
		)
		(fp_line
			(start -3.750056 5.500116)
			(end 3.750056 5.500116)
			(stroke
				(width 0.1)
				(type default)
			)
			(layer "F.Fab")
		)
		(fp_line
			(start -3.750056 -5.500116)
			(end -3.750056 5.500116)
			(stroke
				(width 0.1)
				(type default)
			)
			(layer "F.Fab")
		)
		(fp_poly
			(pts
				(xy -4.9276 -4.757928) (xy -4.9276 -3.741928) (xy -3.9116 -4.249928)
			)
			(stroke
				(width 0)
				(type default)
			)
			(fill yes)
			(layer "F.Fab")
		)
		(pad "1" smd rect
			(at 0 -4.249928 90)
			(size 2.413 4.5212)
			(layers "F.Cu" "F.Mask" "F.Paste")
			(net "SW_PVDDCR_CPU0_P1_SW4")
		)
		(pad "2" smd rect
			(at 0 -1.175004 90)
			(size 1.3716 4.5212)
			(layers "F.Cu" "F.Mask" "F.Paste")
			(net "IND_CPU0_P1_CPL3")
		)
		(pad "3" smd rect
			(at 0 1.175004 90)
			(size 1.3716 4.5212)
			(layers "F.Cu" "F.Mask" "F.Paste")
			(net "GND")
		)
		(pad "4" smd rect
			(at 0 4.249928 90)
			(size 2.413 4.5212)
			(layers "F.Cu" "F.Mask" "F.Paste")
			(net "PVDDCR_CPU0_P1")
		)
	)
	(footprint ""
		(layer "F.Cu")
		(at 321.112896 -378.95403 -90)
		(property "Reference" "C909"
			(at 0 0 270)
			(layer "F.SilkS")
			(hide yes)
			(effects
				(font
					(size 1.27 1.27)
				)
			)
		)
		(property "Value" ""
			(at 0 0 270)
			(layer "F.Fab")
			(effects
				(font
					(size 1.27 1.27)
				)
			)
		)
		(duplicate_pad_numbers_are_jumpers no)
		(fp_line
			(start -0.299974 0.150114)
			(end -0.299974 -0.150114)
			(stroke
				(width 0.1)
				(type default)
			)
			(layer "F.Fab")
		)
		(fp_line
			(start 0.299974 0.150114)
			(end -0.299974 0.150114)
			(stroke
				(width 0.1)
				(type default)
			)
			(layer "F.Fab")
		)
		(fp_line
			(start -0.299974 -0.150114)
			(end 0.299974 -0.150114)
			(stroke
				(width 0.1)
				(type default)
			)
			(layer "F.Fab")
		)
		(fp_line
			(start 0.299974 -0.150114)
			(end 0.299974 0.150114)
			(stroke
				(width 0.1)
				(type default)
			)
			(layer "F.Fab")
		)
		(pad "1" smd rect
			(at -0.2667 0 270)
			(size 0.3048 0.381)
			(layers "F.Cu" "F.Mask" "F.Paste")
			(net "P5E_CPU0_P0_TX_C_DP<12>")
		)
		(pad "2" smd rect
			(at 0.2667 0 270)
			(size 0.3048 0.381)
			(layers "F.Cu" "F.Mask" "F.Paste")
			(net "P5E_CPU0_P0_TX_DP<12>")
		)
	)
	(footprint ""
		(layer "F.Cu")
		(at 66.726054 -334.998314 -90)
		(property "Reference" "PC402_C1P1_3"
			(at 0 0 270)
			(layer "F.SilkS")
			(hide yes)
			(effects
				(font
					(size 1.27 1.27)
				)
			)
		)
		(property "Value" ""
			(at 0 0 270)
			(layer "F.Fab")
			(effects
				(font
					(size 1.27 1.27)
				)
			)
		)
		(duplicate_pad_numbers_are_jumpers no)
		(fp_line
			(start -0.7874 0.4064)
			(end -0.7874 -0.4064)
			(stroke
				(width 0.1524)
				(type default)
			)
			(layer "F.SilkS")
		)
		(fp_line
			(start 0.7874 0.4064)
			(end -0.7874 0.4064)
			(stroke
				(width 0.1524)
				(type default)
			)
			(layer "F.SilkS")
		)
		(fp_line
			(start -0.7874 -0.4064)
			(end 0.7874 -0.4064)
			(stroke
				(width 0.1524)
				(type default)
			)
			(layer "F.SilkS")
		)
		(fp_line
			(start 0.7874 -0.4064)
			(end 0.7874 0.4064)
			(stroke
				(width 0.1524)
				(type default)
			)
			(layer "F.SilkS")
		)
		(fp_line
			(start -0.67945 0.3048)
			(end -0.67945 -0.305054)
			(stroke
				(width 0.1)
				(type default)
			)
			(layer "F.Fab")
		)
		(fp_line
			(start -0.12065 0.3048)
			(end -0.67945 0.3048)
			(stroke
				(width 0.1)
				(type default)
			)
			(layer "F.Fab")
		)
		(fp_line
			(start 0.120396 0.3048)
			(end 0.120396 0.2794)
			(stroke
				(width 0.1)
				(type default)
			)
			(layer "F.Fab")
		)
		(fp_line
			(start 0.67945 0.3048)
			(end 0.120396 0.3048)
			(stroke
				(width 0.1)
				(type default)
			)
			(layer "F.Fab")
		)
		(fp_line
			(start -0.12065 0.2794)
			(end -0.12065 0.3048)
			(stroke
				(width 0.1)
				(type default)
			)
			(layer "F.Fab")
		)
		(fp_line
			(start 0.120396 0.2794)
			(end -0.12065 0.2794)
			(stroke
				(width 0.1)
				(type default)
			)
			(layer "F.Fab")
		)
		(fp_line
			(start -0.12065 -0.2794)
			(end 0.12065 -0.2794)
			(stroke
				(width 0.1)
				(type default)
			)
			(layer "F.Fab")
		)
		(fp_line
			(start 0.12065 -0.2794)
			(end 0.12065 -0.3048)
			(stroke
				(width 0.1)
				(type default)
			)
			(layer "F.Fab")
		)
		(fp_line
			(start 0.12065 -0.3048)
			(end 0.67945 -0.3048)
			(stroke
				(width 0.1)
				(type default)
			)
			(layer "F.Fab")
		)
		(fp_line
			(start 0.67945 -0.3048)
			(end 0.67945 0.3048)
			(stroke
				(width 0.1)
				(type default)
			)
			(layer "F.Fab")
		)
		(fp_line
			(start -0.67945 -0.305054)
			(end -0.12065 -0.305054)
			(stroke
				(width 0.1)
				(type default)
			)
			(layer "F.Fab")
		)
		(fp_line
			(start -0.12065 -0.305054)
			(end -0.12065 -0.2794)
			(stroke
				(width 0.1)
				(type default)
			)
			(layer "F.Fab")
		)
		(pad "1" smd circle
			(at -0.40005 0 270)
			(size 0 0)
			(layers "F.Cu" "F.Mask" "F.Paste")
			(net "PVDDCR_CPU1_P1_PVCC")
		)
		(pad "2" smd circle
			(at 0.40005 0 270)
			(size 0 0)
			(layers "F.Cu" "F.Mask" "F.Paste")
			(net "GND")
		)
	)
)
